(kicad_pcb
	(version 20260206)
	(generator "pcbnew")
	(generator_version "10.0")
	(general
		(thickness 1.6)
		(legacy_teardrops no)
	)
	(paper "A4")
	(title_block
		(title "Wiwynn_Tioga_Pass_MB.brd")
		(comment 1 "Tioga Pass / footprints 2537-2544 of 4770")
	)
	(layers
		(0 "F.Cu" signal "TOP")
		(4 "In1.Cu" signal "L2GND")
		(6 "In2.Cu" signal "L3")
		(8 "In3.Cu" signal "L4GND")
		(10 "In4.Cu" signal "L5")
		(12 "In5.Cu" signal "L6GND")
		(14 "In6.Cu" signal "L7VCC")
		(16 "In7.Cu" signal "L8VCC")
		(18 "In8.Cu" signal "L9GND")
		(20 "In9.Cu" signal "L10")
		(22 "In10.Cu" signal "L11GND")
		(24 "In11.Cu" signal "L12")
		(26 "In12.Cu" signal "L13GND")
		(2 "B.Cu" signal "BOTTOM")
		(9 "F.Adhes" user "F.Adhesive")
		(11 "B.Adhes" user "B.Adhesive")
		(13 "F.Paste" user "Package Geometry/Pastemask Top")
		(15 "B.Paste" user "Package Geometry/Pastemask Bottom")
		(5 "F.SilkS" user "Ref Des/Silkscreen Top")
		(7 "B.SilkS" user "Ref Des/Silkscreen Bottom")
		(1 "F.Mask" user "Board Geometry/Soldermask Top")
		(3 "B.Mask" user "Board Geometry/Soldermask Bottom")
		(17 "Dwgs.User" user "User.Drawings")
		(19 "Cmts.User" user "User.Comments")
		(21 "Eco1.User" user "User.Eco1")
		(23 "Eco2.User" user "User.Eco2")
		(25 "Edge.Cuts" user "Board Geometry/Outline")
		(27 "Margin" user)
		(31 "F.CrtYd" user "Package Geometry/Place Bound Top")
		(29 "B.CrtYd" user "Package Geometry/Place Bound Bottom")
		(35 "F.Fab" user "Ref Des/Assembly Top")
		(33 "B.Fab" user "Ref Des/Assembly Bottom")
	)
	(footprint ""
		(layer "B.Cu")
		(at 462.8134 -52.432458)
		(property "Reference" "C1R2"
			(at 0 0 0)
			(layer "B.SilkS")
			(hide yes)
			(effects
				(font
					(size 1.27 1.27)
				)
				(justify mirror)
			)
		)
		(property "Value" ""
			(at 0 0 0)
			(layer "B.Fab")
			(effects
				(font
					(size 1.27 1.27)
				)
				(justify mirror)
			)
		)
		(duplicate_pad_numbers_are_jumpers no)
		(fp_poly
			(pts
				(xy -0.3048 -0.1016) (xy -0.3048 0.9906) (xy 0.3048 0.9906) (xy 0.3048 -0.1016)
			)
			(stroke
				(width 0)
				(type default)
			)
			(fill no)
			(layer "B.CrtYd")
		)
		(fp_line
			(start -0.3048 -0.1016)
			(end 0.3048 -0.1016)
			(stroke
				(width 0.1)
				(type default)
			)
			(layer "B.Fab")
		)
		(fp_line
			(start -0.3048 0.9906)
			(end -0.3048 -0.1016)
			(stroke
				(width 0.1)
				(type default)
			)
			(layer "B.Fab")
		)
		(fp_line
			(start 0.3048 -0.1016)
			(end 0.3048 0.9906)
			(stroke
				(width 0.1)
				(type default)
			)
			(layer "B.Fab")
		)
		(fp_line
			(start 0.3048 0.9906)
			(end -0.3048 0.9906)
			(stroke
				(width 0.1)
				(type default)
			)
			(layer "B.Fab")
		)
		(pad "1" smd rect
			(at 0 0 180)
			(size 0.508 0.508)
			(layers "B.Cu" "B.Mask" "B.Paste")
			(net "P3E_CPU0_PE3_OCP_TXP<0>")
		)
		(pad "2" smd rect
			(at 0 0.889 180)
			(size 0.508 0.508)
			(layers "B.Cu" "B.Mask" "B.Paste")
			(net "P3E_OCP_CPU0_PE3_C_TXP<0>")
		)
		(zone
			(layer "B.Cu")
			(hatch none 0.5)
			(connect_pads
				(clearance 0)
			)
			(min_thickness 0.25)
			(keepout
				(tracks allowed)
				(vias not_allowed)
				(pads allowed)
				(copperpour not_allowed)
				(footprints allowed)
			)
			(placement
				(enabled no)
				(sheetname "")
			)
			(fill
				(thermal_gap 0.5)
				(thermal_bridge_width 0.5)
				(island_removal_mode 0)
			)
			(polygon
				(pts
					(xy 463.0674 -52.178458) (xy 462.5594 -52.178458) (xy 462.5594 -51.797458) (xy 463.0674 -51.797458)
				)
			)
		)
		(zone
			(layer "B.Cu")
			(hatch none 0.5)
			(connect_pads
				(clearance 0)
			)
			(min_thickness 0.25)
			(keepout
				(tracks not_allowed)
				(vias allowed)
				(pads allowed)
				(copperpour not_allowed)
				(footprints allowed)
			)
			(placement
				(enabled no)
				(sheetname "")
			)
			(fill
				(thermal_gap 0.5)
				(thermal_bridge_width 0.5)
				(island_removal_mode 0)
			)
			(polygon
				(pts
					(xy 463.0674 -51.797458) (xy 462.5594 -51.797458) (xy 462.5594 -52.178458) (xy 463.0674 -52.178458)
				)
			)
		)
	)
	(footprint ""
		(layer "B.Cu")
		(at 413.2326 -37.5412)
		(property "Reference" "C25W25"
			(at 0.8382 -0.67818 0)
			(unlocked yes)
			(layer "B.SilkS")
			(effects
				(font
					(size 0.4064 0.254)
					(thickness 0.1524)
				)
				(justify left mirror)
			)
		)
		(property "Value" ""
			(at 0 0 0)
			(layer "B.Fab")
			(effects
				(font
					(size 1.27 1.27)
				)
				(justify mirror)
			)
		)
		(duplicate_pad_numbers_are_jumpers no)
		(fp_poly
			(pts
				(xy -0.3048 -0.1016) (xy -0.3048 0.9906) (xy 0.3048 0.9906) (xy 0.3048 -0.1016)
			)
			(stroke
				(width 0)
				(type default)
			)
			(fill no)
			(layer "B.CrtYd")
		)
		(fp_line
			(start -0.3048 -0.1016)
			(end 0.3048 -0.1016)
			(stroke
				(width 0.1)
				(type default)
			)
			(layer "B.Fab")
		)
		(fp_line
			(start -0.3048 0.9906)
			(end -0.3048 -0.1016)
			(stroke
				(width 0.1)
				(type default)
			)
			(layer "B.Fab")
		)
		(fp_line
			(start 0.3048 -0.1016)
			(end 0.3048 0.9906)
			(stroke
				(width 0.1)
				(type default)
			)
			(layer "B.Fab")
		)
		(fp_line
			(start 0.3048 0.9906)
			(end -0.3048 0.9906)
			(stroke
				(width 0.1)
				(type default)
			)
			(layer "B.Fab")
		)
		(pad "1" smd rect
			(at 0 0 180)
			(size 0.508 0.508)
			(layers "B.Cu" "B.Mask" "B.Paste")
			(net "P1V15_AUX_BMC")
		)
		(pad "2" smd rect
			(at 0 0.889 180)
			(size 0.508 0.508)
			(layers "B.Cu" "B.Mask" "B.Paste")
			(net "GND")
		)
		(zone
			(layer "B.Cu")
			(hatch none 0.5)
			(connect_pads
				(clearance 0)
			)
			(min_thickness 0.25)
			(keepout
				(tracks allowed)
				(vias not_allowed)
				(pads allowed)
				(copperpour not_allowed)
				(footprints allowed)
			)
			(placement
				(enabled no)
				(sheetname "")
			)
			(fill
				(thermal_gap 0.5)
				(thermal_bridge_width 0.5)
				(island_removal_mode 0)
			)
			(polygon
				(pts
					(xy 413.4866 -37.2872) (xy 412.9786 -37.2872) (xy 412.9786 -36.9062) (xy 413.4866 -36.9062)
				)
			)
		)
		(zone
			(layer "B.Cu")
			(hatch none 0.5)
			(connect_pads
				(clearance 0)
			)
			(min_thickness 0.25)
			(keepout
				(tracks not_allowed)
				(vias allowed)
				(pads allowed)
				(copperpour not_allowed)
				(footprints allowed)
			)
			(placement
				(enabled no)
				(sheetname "")
			)
			(fill
				(thermal_gap 0.5)
				(thermal_bridge_width 0.5)
				(island_removal_mode 0)
			)
			(polygon
				(pts
					(xy 413.4866 -36.9062) (xy 412.9786 -36.9062) (xy 412.9786 -37.2872) (xy 413.4866 -37.2872)
				)
			)
		)
	)
	(footprint ""
		(layer "B.Cu")
		(at 320.194432 -8.128 90)
		(property "Reference" "C4U1"
			(at 0 0 90)
			(layer "B.SilkS")
			(hide yes)
			(effects
				(font
					(size 1.27 1.27)
				)
				(justify mirror)
			)
		)
		(property "Value" ""
			(at 0 0 90)
			(layer "B.Fab")
			(effects
				(font
					(size 1.27 1.27)
				)
				(justify mirror)
			)
		)
		(duplicate_pad_numbers_are_jumpers no)
		(fp_poly
			(pts
				(xy 0.4953 -0.2032) (xy -0.4953 -0.2032) (xy -0.4953 1.6002) (xy 0.4953 1.6002)
			)
			(stroke
				(width 0)
				(type default)
			)
			(fill no)
			(layer "B.CrtYd")
		)
		(fp_line
			(start 0.4953 -0.2032)
			(end -0.4953 -0.2032)
			(stroke
				(width 0.1)
				(type default)
			)
			(layer "B.Fab")
		)
		(fp_line
			(start -0.4953 -0.2032)
			(end -0.4953 1.6002)
			(stroke
				(width 0.1)
				(type default)
			)
			(layer "B.Fab")
		)
		(fp_line
			(start 0.4953 1.6002)
			(end 0.4953 -0.2032)
			(stroke
				(width 0.1)
				(type default)
			)
			(layer "B.Fab")
		)
		(fp_line
			(start -0.4953 1.6002)
			(end 0.4953 1.6002)
			(stroke
				(width 0.1)
				(type default)
			)
			(layer "B.Fab")
		)
		(pad "1" smd rect
			(at 0 0 270)
			(size 0.762 0.889)
			(layers "B.Cu" "B.Mask" "B.Paste")
			(net "PVPP_ABC")
		)
		(pad "2" smd rect
			(at 0 1.397 270)
			(size 0.762 0.889)
			(layers "B.Cu" "B.Mask" "B.Paste")
			(net "GND")
		)
		(zone
			(layer "B.Cu")
			(hatch none 0.5)
			(connect_pads
				(clearance 0)
			)
			(min_thickness 0.25)
			(keepout
				(tracks not_allowed)
				(vias allowed)
				(pads allowed)
				(copperpour not_allowed)
				(footprints allowed)
			)
			(placement
				(enabled no)
				(sheetname "")
			)
			(fill
				(thermal_gap 0.5)
				(thermal_bridge_width 0.5)
				(island_removal_mode 0)
			)
			(polygon
				(pts
					(xy 320.638932 -8.509) (xy 320.638932 -7.747) (xy 321.146932 -7.747) (xy 321.146932 -8.509)
				)
			)
		)
	)
	(footprint ""
		(layer "B.Cu")
		(at 0.889 -135.763 90)
		(property "Reference" "R9L9"
			(at 0 0 90)
			(layer "B.SilkS")
			(hide yes)
			(effects
				(font
					(size 1.27 1.27)
				)
				(justify mirror)
			)
		)
		(property "Value" ""
			(at 0 0 90)
			(layer "B.Fab")
			(effects
				(font
					(size 1.27 1.27)
				)
				(justify mirror)
			)
		)
		(duplicate_pad_numbers_are_jumpers no)
		(fp_rect
			(start 0.2794 -0.1016)
			(end -0.2794 0.9906)
			(stroke
				(width 0)
				(type default)
			)
			(fill no)
			(layer "B.CrtYd")
		)
		(fp_line
			(start 0.2794 -0.1016)
			(end 0.2794 0.9906)
			(stroke
				(width 0.1)
				(type default)
			)
			(layer "B.Fab")
		)
		(fp_line
			(start -0.2794 -0.1016)
			(end 0.2794 -0.1016)
			(stroke
				(width 0.1)
				(type default)
			)
			(layer "B.Fab")
		)
		(fp_line
			(start 0.2794 0.9906)
			(end -0.2794 0.9906)
			(stroke
				(width 0.1)
				(type default)
			)
			(layer "B.Fab")
		)
		(fp_line
			(start -0.2794 0.9906)
			(end -0.2794 -0.1016)
			(stroke
				(width 0.1)
				(type default)
			)
			(layer "B.Fab")
		)
		(pad "1" smd rect
			(at 0 0 270)
			(size 0.508 0.508)
			(layers "B.Cu" "B.Mask" "B.Paste")
			(net "VR_PVDDQ_KLM_PH1_VCIN")
		)
		(pad "2" smd rect
			(at 0 0.889 270)
			(size 0.508 0.508)
			(layers "B.Cu" "B.Mask" "B.Paste")
			(net "P5V_STBY")
		)
		(zone
			(layer "B.Cu")
			(hatch none 0.5)
			(connect_pads
				(clearance 0)
			)
			(min_thickness 0.25)
			(keepout
				(tracks allowed)
				(vias not_allowed)
				(pads allowed)
				(copperpour not_allowed)
				(footprints allowed)
			)
			(placement
				(enabled no)
				(sheetname "")
			)
			(fill
				(thermal_gap 0.5)
				(thermal_bridge_width 0.5)
				(island_removal_mode 0)
			)
			(polygon
				(pts
					(xy 1.143 -136.017) (xy 1.143 -135.509) (xy 1.524 -135.509) (xy 1.524 -136.017)
				)
			)
		)
		(zone
			(layer "B.Cu")
			(hatch none 0.5)
			(connect_pads
				(clearance 0)
			)
			(min_thickness 0.25)
			(keepout
				(tracks not_allowed)
				(vias allowed)
				(pads allowed)
				(copperpour not_allowed)
				(footprints allowed)
			)
			(placement
				(enabled no)
				(sheetname "")
			)
			(fill
				(thermal_gap 0.5)
				(thermal_bridge_width 0.5)
				(island_removal_mode 0)
			)
			(polygon
				(pts
					(xy 1.143 -136.017) (xy 1.143 -135.509) (xy 1.524 -135.509) (xy 1.524 -136.017)
				)
			)
		)
	)
	(footprint ""
		(layer "B.Cu")
		(at 345.8972 -112.7252 -90)
		(property "Reference" "C3M46"
			(at 0 0 90)
			(layer "B.SilkS")
			(hide yes)
			(effects
				(font
					(size 1.27 1.27)
				)
				(justify mirror)
			)
		)
		(property "Value" ""
			(at 0 0 90)
			(layer "B.Fab")
			(effects
				(font
					(size 1.27 1.27)
				)
				(justify mirror)
			)
		)
		(duplicate_pad_numbers_are_jumpers no)
		(fp_poly
			(pts
				(xy -0.3048 -0.1016) (xy -0.3048 0.9906) (xy 0.3048 0.9906) (xy 0.3048 -0.1016)
			)
			(stroke
				(width 0)
				(type default)
			)
			(fill no)
			(layer "B.CrtYd")
		)
		(fp_line
			(start -0.3048 0.9906)
			(end -0.3048 -0.1016)
			(stroke
				(width 0.1)
				(type default)
			)
			(layer "B.Fab")
		)
		(fp_line
			(start 0.3048 0.9906)
			(end -0.3048 0.9906)
			(stroke
				(width 0.1)
				(type default)
			)
			(layer "B.Fab")
		)
		(fp_line
			(start -0.3048 -0.1016)
			(end 0.3048 -0.1016)
			(stroke
				(width 0.1)
				(type default)
			)
			(layer "B.Fab")
		)
		(fp_line
			(start 0.3048 -0.1016)
			(end 0.3048 0.9906)
			(stroke
				(width 0.1)
				(type default)
			)
			(layer "B.Fab")
		)
		(pad "1" smd rect
			(at 0 0 90)
			(size 0.508 0.508)
			(layers "B.Cu" "B.Mask" "B.Paste")
			(net "PVCCIOMCP_CPU0")
		)
		(pad "2" smd rect
			(at 0 0.889 90)
			(size 0.508 0.508)
			(layers "B.Cu" "B.Mask" "B.Paste")
			(net "GND")
		)
		(zone
			(layer "B.Cu")
			(hatch none 0.5)
			(connect_pads
				(clearance 0)
			)
			(min_thickness 0.25)
			(keepout
				(tracks not_allowed)
				(vias allowed)
				(pads allowed)
				(copperpour not_allowed)
				(footprints allowed)
			)
			(placement
				(enabled no)
				(sheetname "")
			)
			(fill
				(thermal_gap 0.5)
				(thermal_bridge_width 0.5)
				(island_removal_mode 0)
			)
			(polygon
				(pts
					(xy 345.2622 -112.4712) (xy 345.2622 -112.9792) (xy 345.6432 -112.9792) (xy 345.6432 -112.4712)
				)
			)
		)
		(zone
			(layer "B.Cu")
			(hatch none 0.5)
			(connect_pads
				(clearance 0)
			)
			(min_thickness 0.25)
			(keepout
				(tracks allowed)
				(vias not_allowed)
				(pads allowed)
				(copperpour not_allowed)
				(footprints allowed)
			)
			(placement
				(enabled no)
				(sheetname "")
			)
			(fill
				(thermal_gap 0.5)
				(thermal_bridge_width 0.5)
				(island_removal_mode 0)
			)
			(polygon
				(pts
					(xy 345.6432 -112.4712) (xy 345.6432 -112.9792) (xy 345.2622 -112.9792) (xy 345.2622 -112.4712)
				)
			)
		)
	)
	(footprint ""
		(layer "B.Cu")
		(at 470.027 -60.198 -90)
		(property "Reference" "R1R19"
			(at 0 0 90)
			(layer "B.SilkS")
			(hide yes)
			(effects
				(font
					(size 1.27 1.27)
				)
				(justify mirror)
			)
		)
		(property "Value" ""
			(at 0 0 90)
			(layer "B.Fab")
			(effects
				(font
					(size 1.27 1.27)
				)
				(justify mirror)
			)
		)
		(duplicate_pad_numbers_are_jumpers no)
		(fp_poly
			(pts
				(xy 0.2794 -0.1016) (xy -0.2794 -0.1016) (xy -0.2794 0.9906) (xy 0.2794 0.9906)
			)
			(stroke
				(width 0)
				(type default)
			)
			(fill no)
			(layer "B.CrtYd")
		)
		(fp_line
			(start -0.2794 0.9906)
			(end -0.2794 -0.1016)
			(stroke
				(width 0.1)
				(type default)
			)
			(layer "B.Fab")
		)
		(fp_line
			(start 0.2794 0.9906)
			(end -0.2794 0.9906)
			(stroke
				(width 0.1)
				(type default)
			)
			(layer "B.Fab")
		)
		(fp_line
			(start -0.2794 -0.1016)
			(end 0.2794 -0.1016)
			(stroke
				(width 0.1)
				(type default)
			)
			(layer "B.Fab")
		)
		(fp_line
			(start 0.2794 -0.1016)
			(end 0.2794 0.9906)
			(stroke
				(width 0.1)
				(type default)
			)
			(layer "B.Fab")
		)
		(pad "1" smd rect
			(at 0 0 90)
			(size 0.508 0.508)
			(layers "B.Cu" "B.Mask" "B.Paste")
			(net "P3V3_STBY")
		)
		(pad "2" smd rect
			(at 0 0.889 90)
			(size 0.508 0.508)
			(layers "B.Cu" "B.Mask" "B.Paste")
			(net "SMB_PCH_MEZZ_LOM0_SDA")
		)
		(zone
			(layer "B.Cu")
			(hatch none 0.5)
			(connect_pads
				(clearance 0)
			)
			(min_thickness 0.25)
			(keepout
				(tracks not_allowed)
				(vias allowed)
				(pads allowed)
				(copperpour not_allowed)
				(footprints allowed)
			)
			(placement
				(enabled no)
				(sheetname "")
			)
			(fill
				(thermal_gap 0.5)
				(thermal_bridge_width 0.5)
				(island_removal_mode 0)
			)
			(polygon
				(pts
					(xy 469.392 -59.944) (xy 469.392 -60.452) (xy 469.773 -60.452) (xy 469.773 -59.944)
				)
			)
		)
		(zone
			(layer "B.Cu")
			(hatch none 0.5)
			(connect_pads
				(clearance 0)
			)
			(min_thickness 0.25)
			(keepout
				(tracks allowed)
				(vias not_allowed)
				(pads allowed)
				(copperpour not_allowed)
				(footprints allowed)
			)
			(placement
				(enabled no)
				(sheetname "")
			)
			(fill
				(thermal_gap 0.5)
				(thermal_bridge_width 0.5)
				(island_removal_mode 0)
			)
			(polygon
				(pts
					(xy 469.773 -59.944) (xy 469.773 -60.452) (xy 469.392 -60.452) (xy 469.392 -59.944)
				)
			)
		)
	)
	(footprint ""
		(layer "B.Cu")
		(at 197.866 -98.933 90)
		(property "Reference" "C6N3"
			(at 0 0 90)
			(layer "B.SilkS")
			(hide yes)
			(effects
				(font
					(size 1.27 1.27)
				)
				(justify mirror)
			)
		)
		(property "Value" ""
			(at 0 0 90)
			(layer "B.Fab")
			(effects
				(font
					(size 1.27 1.27)
				)
				(justify mirror)
			)
		)
		(duplicate_pad_numbers_are_jumpers no)
		(fp_rect
			(start 0.7239 1.9939)
			(end -0.7239 -0.2159)
			(stroke
				(width 0)
				(type default)
			)
			(fill no)
			(layer "B.CrtYd")
		)
		(fp_line
			(start 0.7239 -0.2159)
			(end 0.7239 1.9939)
			(stroke
				(width 0.1)
				(type default)
			)
			(layer "B.Fab")
		)
		(fp_line
			(start -0.7239 -0.2159)
			(end 0.7239 -0.2159)
			(stroke
				(width 0.1)
				(type default)
			)
			(layer "B.Fab")
		)
		(fp_line
			(start 0.7239 1.9939)
			(end -0.7239 1.9939)
			(stroke
				(width 0.1)
				(type default)
			)
			(layer "B.Fab")
		)
		(fp_line
			(start -0.7239 1.9939)
			(end -0.7239 -0.2159)
			(stroke
				(width 0.1)
				(type default)
			)
			(layer "B.Fab")
		)
		(pad "1" smd rect
			(at 0 0 270)
			(size 1.27 1.016)
			(layers "B.Cu" "B.Mask" "B.Paste")
			(net "VR_FET_SW_P12V_STBY_PVCCIN_CPU0")
		)
		(pad "2" smd rect
			(at 0 1.778 270)
			(size 1.27 1.016)
			(layers "B.Cu" "B.Mask" "B.Paste")
			(net "GND")
		)
		(zone
			(layer "B.Cu")
			(hatch none 0.5)
			(connect_pads
				(clearance 0)
			)
			(min_thickness 0.25)
			(keepout
				(tracks not_allowed)
				(vias allowed)
				(pads allowed)
				(copperpour not_allowed)
				(footprints allowed)
			)
			(placement
				(enabled no)
				(sheetname "")
			)
			(fill
				(thermal_gap 0.5)
				(thermal_bridge_width 0.5)
				(island_removal_mode 0)
			)
			(polygon
				(pts
					(xy 199.136 -99.568) (xy 198.374 -99.568) (xy 198.374 -98.298) (xy 199.136 -98.298)
				)
			)
		)
	)
	(footprint ""
		(layer "B.Cu")
		(at 394.335 -67.056 90)
		(property "Reference" "R7W5"
			(at 0.8382 -0.67818 90)
			(unlocked yes)
			(layer "B.SilkS")
			(effects
				(font
					(size 0.4064 0.254)
					(thickness 0.1524)
				)
				(justify left mirror)
			)
		)
		(property "Value" ""
			(at 0 0 90)
			(layer "B.Fab")
			(effects
				(font
					(size 1.27 1.27)
				)
				(justify mirror)
			)
		)
		(duplicate_pad_numbers_are_jumpers no)
		(fp_poly
			(pts
				(xy 0.2794 -0.1016) (xy -0.2794 -0.1016) (xy -0.2794 0.9906) (xy 0.2794 0.9906)
			)
			(stroke
				(width 0)
				(type default)
			)
			(fill no)
			(layer "B.CrtYd")
		)
		(fp_line
			(start 0.2794 -0.1016)
			(end 0.2794 0.9906)
			(stroke
				(width 0.1)
				(type default)
			)
			(layer "B.Fab")
		)
		(fp_line
			(start -0.2794 -0.1016)
			(end 0.2794 -0.1016)
			(stroke
				(width 0.1)
				(type default)
			)
			(layer "B.Fab")
		)
		(fp_line
			(start 0.2794 0.9906)
			(end -0.2794 0.9906)
			(stroke
				(width 0.1)
				(type default)
			)
			(layer "B.Fab")
		)
		(fp_line
			(start -0.2794 0.9906)
			(end -0.2794 -0.1016)
			(stroke
				(width 0.1)
				(type default)
			)
			(layer "B.Fab")
		)
		(pad "1" smd rect
			(at 0 0 270)
			(size 0.508 0.508)
			(layers "B.Cu" "B.Mask" "B.Paste")
			(net "SPI_SWITCH_CS0_N")
		)
		(pad "2" smd rect
			(at 0 0.889 270)
			(size 0.508 0.508)
			(layers "B.Cu" "B.Mask" "B.Paste")
			(net "SPI_CS0_PRIMARY_R_N")
		)
		(zone
			(layer "B.Cu")
			(hatch none 0.5)
			(connect_pads
				(clearance 0)
			)
			(min_thickness 0.25)
			(keepout
				(tracks allowed)
				(vias not_allowed)
				(pads allowed)
				(copperpour not_allowed)
				(footprints allowed)
			)
			(placement
				(enabled no)
				(sheetname "")
			)
			(fill
				(thermal_gap 0.5)
				(thermal_bridge_width 0.5)
				(island_removal_mode 0)
			)
			(polygon
				(pts
					(xy 394.589 -67.31) (xy 394.589 -66.802) (xy 394.97 -66.802) (xy 394.97 -67.31)
				)
			)
		)
		(zone
			(layer "B.Cu")
			(hatch none 0.5)
			(connect_pads
				(clearance 0)
			)
			(min_thickness 0.25)
			(keepout
				(tracks not_allowed)
				(vias allowed)
				(pads allowed)
				(copperpour not_allowed)
				(footprints allowed)
			)
			(placement
				(enabled no)
				(sheetname "")
			)
			(fill
				(thermal_gap 0.5)
				(thermal_bridge_width 0.5)
				(island_removal_mode 0)
			)
			(polygon
				(pts
					(xy 394.97 -67.31) (xy 394.97 -66.802) (xy 394.589 -66.802) (xy 394.589 -67.31)
				)
			)
		)
	)
)
